# SCM (Grand Teton) — schematic netlist excerpt (pin names and nets, part order shuffled) for the footprints in the layout excerpt that follows; sources: Cadence DE-HDL packaged netlist, KiCad conversion of 12092022_DA0F0TMDCD0_F0T_Management_Board_D_brd_V3_OCP.brd

R742  Q_RES  4.7K 1% EMPTY  pkg 0402LF  page 30 : A = P3V3_AUX ; B = SPA_SOUT_SW_BUF
R330  Q_RES  120 1% CHIP  pkg 0402LF  page 20 : A = GND ; B = M_BMC_DDR4_MA<4>

(kicad_pcb
	(version 20260206)
	(generator "pcbnew")
	(generator_version "10.0")
	(general
		(thickness 1.6)
		(legacy_teardrops no)
	)
	(paper "A4")
	(title_block
		(title "12092022_DA0F0TMDCD0_F0T_Management_Board_D_brd_V3_OCP.brd")
		(comment 1 "Grand Teton / footprints 452-453 of 1440")
	)
	(layers
		(0 "F.Cu" signal "TOP")
		(4 "In1.Cu" signal "GND")
		(6 "In2.Cu" signal "IN1")
		(8 "In3.Cu" signal "GND1")
		(10 "In4.Cu" signal "IN2")
		(12 "In5.Cu" signal "VCC")
		(14 "In6.Cu" signal "VCC1")
		(16 "In7.Cu" signal "IN3")
		(18 "In8.Cu" signal "GND2")
		(20 "In9.Cu" signal "IN4")
		(22 "In10.Cu" signal "GND3")
		(2 "B.Cu" signal "BOTTOM")
		(9 "F.Adhes" user "F.Adhesive")
		(11 "B.Adhes" user "B.Adhesive")
		(13 "F.Paste" user "Package Geometry/Pastemask Top")
		(15 "B.Paste" user "Package Geometry/Pastemask Bottom")
		(5 "F.SilkS" user "Ref Des/Silkscreen Top")
		(7 "B.SilkS" user "Ref Des/Silkscreen Bottom")
		(1 "F.Mask" user "Board Geometry/Soldermask Top")
		(3 "B.Mask" user "Board Geometry/Soldermask Bottom")
		(17 "Dwgs.User" user "User.Drawings")
		(19 "Cmts.User" user "User.Comments")
		(21 "Eco1.User" user "User.Eco1")
		(23 "Eco2.User" user "User.Eco2")
		(25 "Edge.Cuts" user "Board Geometry/Outline")
		(27 "Margin" user)
		(31 "F.CrtYd" user "Package Geometry/Place Bound Top")
		(29 "B.CrtYd" user "Package Geometry/Place Bound Bottom")
		(35 "F.Fab" user "Ref Des/Assembly Top")
		(33 "B.Fab" user "Ref Des/Assembly Bottom")
	)
	(footprint ""
		(layer "F.Cu")
		(at 77.707744 -35.527488 90)
		(property "Reference" "R330"
			(at 0 0 90)
			(layer "F.SilkS")
			(hide yes)
			(effects
				(font
					(size 1.27 1.27)
				)
			)
		)
		(property "Value" ""
			(at 0 0 90)
			(layer "F.Fab")
			(effects
				(font
					(size 1.27 1.27)
				)
			)
		)
		(duplicate_pad_numbers_are_jumpers no)
		(fp_line
			(start 0.7874 -0.4064)
			(end 0.7874 0.4064)
			(stroke
				(width 0.1524)
				(type default)
			)
			(layer "F.SilkS")
		)
		(fp_line
			(start -0.7874 -0.4064)
			(end 0.7874 -0.4064)
			(stroke
				(width 0.1524)
				(type default)
			)
			(layer "F.SilkS")
		)
		(fp_line
			(start 0.7874 0.4064)
			(end -0.7874 0.4064)
			(stroke
				(width 0.1524)
				(type default)
			)
			(layer "F.SilkS")
		)
		(fp_line
			(start -0.7874 0.4064)
			(end -0.7874 -0.4064)
			(stroke
				(width 0.1524)
				(type default)
			)
			(layer "F.SilkS")
		)
		(fp_line
			(start -0.12065 -0.305054)
			(end -0.12065 -0.2794)
			(stroke
				(width 0.1)
				(type default)
			)
			(layer "F.Fab")
		)
		(fp_line
			(start -0.67945 -0.305054)
			(end -0.12065 -0.305054)
			(stroke
				(width 0.1)
				(type default)
			)
			(layer "F.Fab")
		)
		(fp_line
			(start 0.67945 -0.3048)
			(end 0.67945 0.3048)
			(stroke
				(width 0.1)
				(type default)
			)
			(layer "F.Fab")
		)
		(fp_line
			(start 0.12065 -0.3048)
			(end 0.67945 -0.3048)
			(stroke
				(width 0.1)
				(type default)
			)
			(layer "F.Fab")
		)
		(fp_line
			(start 0.12065 -0.2794)
			(end 0.12065 -0.3048)
			(stroke
				(width 0.1)
				(type default)
			)
			(layer "F.Fab")
		)
		(fp_line
			(start -0.12065 -0.2794)
			(end 0.12065 -0.2794)
			(stroke
				(width 0.1)
				(type default)
			)
			(layer "F.Fab")
		)
		(fp_line
			(start 0.120396 0.2794)
			(end -0.12065 0.2794)
			(stroke
				(width 0.1)
				(type default)
			)
			(layer "F.Fab")
		)
		(fp_line
			(start -0.12065 0.2794)
			(end -0.12065 0.3048)
			(stroke
				(width 0.1)
				(type default)
			)
			(layer "F.Fab")
		)
		(fp_line
			(start 0.67945 0.3048)
			(end 0.120396 0.3048)
			(stroke
				(width 0.1)
				(type default)
			)
			(layer "F.Fab")
		)
		(fp_line
			(start 0.120396 0.3048)
			(end 0.120396 0.2794)
			(stroke
				(width 0.1)
				(type default)
			)
			(layer "F.Fab")
		)
		(fp_line
			(start -0.12065 0.3048)
			(end -0.67945 0.3048)
			(stroke
				(width 0.1)
				(type default)
			)
			(layer "F.Fab")
		)
		(fp_line
			(start -0.67945 0.3048)
			(end -0.67945 -0.305054)
			(stroke
				(width 0.1)
				(type default)
			)
			(layer "F.Fab")
		)
		(pad "1" smd circle
			(at -0.40005 0 90)
			(size 0 0)
			(layers "F.Cu" "F.Mask" "F.Paste")
			(net "GND")
		)
		(pad "2" smd circle
			(at 0.40005 0 90)
			(size 0 0)
			(layers "F.Cu" "F.Mask" "F.Paste")
			(net "M_BMC_DDR4_MA<4>")
		)
	)
	(footprint ""
		(layer "F.Cu")
		(at 24.7142 -65.8622 -90)
		(property "Reference" "R742"
			(at 0 0 270)
			(layer "F.SilkS")
			(hide yes)
			(effects
				(font
					(size 1.27 1.27)
				)
			)
		)
		(property "Value" ""
			(at 0 0 270)
			(layer "F.Fab")
			(effects
				(font
					(size 1.27 1.27)
				)
			)
		)
		(duplicate_pad_numbers_are_jumpers no)
		(fp_line
			(start -0.7874 0.4064)
			(end -0.7874 -0.4064)
			(stroke
				(width 0.1524)
				(type default)
			)
			(layer "F.SilkS")
		)
		(fp_line
			(start 0.7874 0.4064)
			(end -0.7874 0.4064)
			(stroke
				(width 0.1524)
				(type default)
			)
			(layer "F.SilkS")
		)
		(fp_line
			(start -0.7874 -0.4064)
			(end 0.7874 -0.4064)
			(stroke
				(width 0.1524)
				(type default)
			)
			(layer "F.SilkS")
		)
		(fp_line
			(start 0.7874 -0.4064)
			(end 0.7874 0.4064)
			(stroke
				(width 0.1524)
				(type default)
			)
			(layer "F.SilkS")
		)
		(fp_line
			(start -0.67945 0.3048)
			(end -0.67945 -0.305054)
			(stroke
				(width 0.1)
				(type default)
			)
			(layer "F.Fab")
		)
		(fp_line
			(start -0.12065 0.3048)
			(end -0.67945 0.3048)
			(stroke
				(width 0.1)
				(type default)
			)
			(layer "F.Fab")
		)
		(fp_line
			(start 0.120396 0.3048)
			(end 0.120396 0.2794)
			(stroke
				(width 0.1)
				(type default)
			)
			(layer "F.Fab")
		)
		(fp_line
			(start 0.67945 0.3048)
			(end 0.120396 0.3048)
			(stroke
				(width 0.1)
				(type default)
			)
			(layer "F.Fab")
		)
		(fp_line
			(start -0.12065 0.2794)
			(end -0.12065 0.3048)
			(stroke
				(width 0.1)
				(type default)
			)
			(layer "F.Fab")
		)
		(fp_line
			(start 0.120396 0.2794)
			(end -0.12065 0.2794)
			(stroke
				(width 0.1)
				(type default)
			)
			(layer "F.Fab")
		)
		(fp_line
			(start -0.12065 -0.2794)
			(end 0.12065 -0.2794)
			(stroke
				(width 0.1)
				(type default)
			)
			(layer "F.Fab")
		)
		(fp_line
			(start 0.12065 -0.2794)
			(end 0.12065 -0.3048)
			(stroke
				(width 0.1)
				(type default)
			)
			(layer "F.Fab")
		)
		(fp_line
			(start 0.12065 -0.3048)
			(end 0.67945 -0.3048)
			(stroke
				(width 0.1)
				(type default)
			)
			(layer "F.Fab")
		)
		(fp_line
			(start 0.67945 -0.3048)
			(end 0.67945 0.3048)
			(stroke
				(width 0.1)
				(type default)
			)
			(layer "F.Fab")
		)
		(fp_line
			(start -0.67945 -0.305054)
			(end -0.12065 -0.305054)
			(stroke
				(width 0.1)
				(type default)
			)
			(layer "F.Fab")
		)
		(fp_line
			(start -0.12065 -0.305054)
			(end -0.12065 -0.2794)
			(stroke
				(width 0.1)
				(type default)
			)
			(layer "F.Fab")
		)
		(pad "1" smd circle
			(at -0.40005 0 270)
			(size 0 0)
			(layers "F.Cu" "F.Mask" "F.Paste")
			(net "P3V3_AUX")
		)
		(pad "2" smd circle
			(at 0.40005 0 270)
			(size 0 0)
			(layers "F.Cu" "F.Mask" "F.Paste")
			(net "SPA_SOUT_SW_BUF")
		)
	)
)
